(kicad_pcb
	(version 20260206)
	(generator "pcbnew")
	(generator_version "10.0")
	(general
		(thickness 1.6)
		(legacy_teardrops no)
	)
	(paper "A4")
	(title_block
		(title "Bryce Canyon_R.DPB_16317-1_OCP.brd")
		(comment 1 "Bryce Canyon / footprints 1937-1944 of 2099")
	)
	(layers
		(0 "F.Cu" signal "TOP")
		(4 "In1.Cu" signal "L2GND")
		(6 "In2.Cu" signal "L3")
		(8 "In3.Cu" signal "L4VCC")
		(10 "In4.Cu" signal "L5VCC")
		(12 "In5.Cu" signal "L6")
		(14 "In6.Cu" signal "L7GND")
		(2 "B.Cu" signal "BOTTOM")
		(9 "F.Adhes" user "F.Adhesive")
		(11 "B.Adhes" user "B.Adhesive")
		(13 "F.Paste" user "Package Geometry/Pastemask Top")
		(15 "B.Paste" user "Package Geometry/Pastemask Bottom")
		(5 "F.SilkS" user "Ref Des/Silkscreen Top")
		(7 "B.SilkS" user "Ref Des/Silkscreen Bottom")
		(1 "F.Mask" user "Board Geometry/Soldermask Top")
		(3 "B.Mask" user "Board Geometry/Soldermask Bottom")
		(17 "Dwgs.User" user "User.Drawings")
		(19 "Cmts.User" user "User.Comments")
		(21 "Eco1.User" user "User.Eco1")
		(23 "Eco2.User" user "User.Eco2")
		(25 "Edge.Cuts" user "Board Geometry/Outline")
		(27 "Margin" user)
		(31 "F.CrtYd" user "Package Geometry/Place Bound Top")
		(29 "B.CrtYd" user "Package Geometry/Place Bound Bottom")
		(35 "F.Fab" user "Ref Des/Assembly Top")
		(33 "B.Fab" user "Ref Des/Assembly Bottom")
	)
	(footprint ""
		(layer "F.Cu")
		(at 347.345 -214.376)
		(property "Reference" "R317"
			(at 0 0 0)
			(layer "F.SilkS")
			(hide yes)
			(effects
				(font
					(size 1.27 1.27)
				)
			)
		)
		(property "Value" "91R3F-1-GP"
			(at -0.0254 -2.5146 0)
			(unlocked yes)
			(layer "F.Fab")
			(hide yes)
			(effects
				(font
					(size 1.016 1.016)
					(thickness 0.1524)
				)
			)
		)
		(property "Device Type" "R603H22"
			(at -0.0254 -4.0386 0)
			(unlocked yes)
			(layer "F.Fab")
			(hide yes)
			(effects
				(font
					(size 1.016 1.016)
					(thickness 0.1524)
				)
			)
		)
		(duplicate_pad_numbers_are_jumpers no)
		(fp_line
			(start -0.4826 0)
			(end -0.2032 0)
			(stroke
				(width 0.2032)
				(type default)
			)
			(layer "F.SilkS")
		)
		(fp_line
			(start 0.2032 0)
			(end 0.4826 0)
			(stroke
				(width 0.2032)
				(type default)
			)
			(layer "F.SilkS")
		)
		(fp_rect
			(start -0.5842 1.3335)
			(end 0.5842 -1.3335)
			(stroke
				(width 0)
				(type default)
			)
			(fill no)
			(layer "F.CrtYd")
		)
		(fp_rect
			(start -0.5842 1.3335)
			(end 0.5842 -1.3335)
			(stroke
				(width 0)
				(type default)
			)
			(fill no)
			(layer "F.Fab")
		)
		(pad "1" smd custom
			(at 0 -0.762)
			(size 0.2159 0.2159)
			(layers "F.Cu" "F.Mask" "F.Paste")
			(net "P5V_B_3")
			(options
				(clearance outline)
				(anchor circle)
			)
			(primitives
				(gr_poly
					(pts
						(arc
							(start -0.3302 -0.4318)
							(mid -0.402042 -0.402042)
							(end -0.4318 -0.3302)
						)
						(arc
							(start -0.4318 0.3302)
							(mid -0.402042 0.402042)
							(end -0.3302 0.4318)
						)
						(arc
							(start 0.3302 0.4318)
							(mid 0.402042 0.402042)
							(end 0.4318 0.3302)
						)
						(arc
							(start 0.4318 -0.3302)
							(mid 0.402042 -0.402042)
							(end 0.3302 -0.4318)
						)
					)
					(width 0)
					(fill yes)
				)
			)
		)
		(pad "2" smd custom
			(at 0 0.762)
			(size 0.2159 0.2159)
			(layers "F.Cu" "F.Mask" "F.Paste")
			(net "DRV_ACT_7")
			(options
				(clearance outline)
				(anchor circle)
			)
			(primitives
				(gr_poly
					(pts
						(arc
							(start -0.3302 -0.4318)
							(mid -0.402042 -0.402042)
							(end -0.4318 -0.3302)
						)
						(arc
							(start -0.4318 0.3302)
							(mid -0.402042 0.402042)
							(end -0.3302 0.4318)
						)
						(arc
							(start 0.3302 0.4318)
							(mid 0.402042 0.402042)
							(end 0.4318 0.3302)
						)
						(arc
							(start 0.4318 -0.3302)
							(mid 0.402042 -0.402042)
							(end 0.3302 -0.4318)
						)
					)
					(width 0)
					(fill yes)
				)
			)
		)
	)
	(footprint ""
		(layer "F.Cu")
		(at 19.37766 -223.994218 90)
		(property "Reference" "C621"
			(at 0 0 90)
			(layer "F.SilkS")
			(hide yes)
			(effects
				(font
					(size 1.27 1.27)
				)
			)
		)
		(property "Value" "SC10U16V5KX-7-GP-U"
			(at -0.0762 -6.1214 90)
			(unlocked yes)
			(layer "F.Fab")
			(hide yes)
			(effects
				(font
					(size 1.016 1.016)
					(thickness 0.1524)
				)
			)
		)
		(property "Device Type" "C805H58"
			(at -0.0762 -8.1534 90)
			(unlocked yes)
			(layer "F.Fab")
			(hide yes)
			(effects
				(font
					(size 1.016 1.016)
					(thickness 0.1524)
				)
			)
		)
		(duplicate_pad_numbers_are_jumpers no)
		(fp_line
			(start 0.635 0)
			(end -0.635 0)
			(stroke
				(width 0.508)
				(type default)
			)
			(layer "F.SilkS")
		)
		(fp_rect
			(start -0.9652 1.778)
			(end 0.9652 -1.778)
			(stroke
				(width 0)
				(type default)
			)
			(fill no)
			(layer "F.CrtYd")
		)
		(fp_poly
			(pts
				(xy -0.9652 -1.778) (xy 0.9652 -1.778) (xy 0.9652 1.778) (xy -0.9652 1.778)
			)
			(stroke
				(width 0)
				(type default)
			)
			(fill no)
			(layer "F.Fab")
		)
		(pad "1" smd rect
			(at 0 -0.9652 90)
			(size 1.397 1.143)
			(layers "F.Cu" "F.Mask" "F.Paste")
			(net "P12V_B_1_VIN_U31")
		)
		(pad "2" smd rect
			(at 0 0.9652 90)
			(size 1.397 1.143)
			(layers "F.Cu" "F.Mask" "F.Paste")
			(net "GND")
		)
	)
	(footprint ""
		(layer "F.Cu")
		(at 327.373996 -370.078 90)
		(property "Reference" "R945"
			(at 0 0 90)
			(layer "F.SilkS")
			(hide yes)
			(effects
				(font
					(size 1.27 1.27)
				)
			)
		)
		(property "Value" "27KR3F-GP"
			(at -0.0254 -2.5146 90)
			(unlocked yes)
			(layer "F.Fab")
			(hide yes)
			(effects
				(font
					(size 1.016 1.016)
					(thickness 0.1524)
				)
			)
		)
		(property "Device Type" "R603H22"
			(at -0.0254 -4.0386 90)
			(unlocked yes)
			(layer "F.Fab")
			(hide yes)
			(effects
				(font
					(size 1.016 1.016)
					(thickness 0.1524)
				)
			)
		)
		(duplicate_pad_numbers_are_jumpers no)
		(fp_line
			(start 0.2032 0)
			(end 0.4826 0)
			(stroke
				(width 0.2032)
				(type default)
			)
			(layer "F.SilkS")
		)
		(fp_line
			(start -0.4826 0)
			(end -0.2032 0)
			(stroke
				(width 0.2032)
				(type default)
			)
			(layer "F.SilkS")
		)
		(fp_rect
			(start -0.5842 1.3335)
			(end 0.5842 -1.3335)
			(stroke
				(width 0)
				(type default)
			)
			(fill no)
			(layer "F.CrtYd")
		)
		(fp_rect
			(start -0.5842 1.3335)
			(end 0.5842 -1.3335)
			(stroke
				(width 0)
				(type default)
			)
			(fill no)
			(layer "F.Fab")
		)
		(pad "1" smd custom
			(at 0 -0.762 90)
			(size 0.2159 0.2159)
			(layers "F.Cu" "F.Mask" "F.Paste")
			(net "FANTACH_R2")
			(options
				(clearance outline)
				(anchor circle)
			)
			(primitives
				(gr_poly
					(pts
						(arc
							(start -0.3302 -0.4318)
							(mid -0.402042 -0.402042)
							(end -0.4318 -0.3302)
						)
						(arc
							(start -0.4318 0.3302)
							(mid -0.402042 0.402042)
							(end -0.3302 0.4318)
						)
						(arc
							(start 0.3302 0.4318)
							(mid 0.402042 0.402042)
							(end 0.4318 0.3302)
						)
						(arc
							(start 0.4318 -0.3302)
							(mid 0.402042 -0.402042)
							(end 0.3302 -0.4318)
						)
					)
					(width 0)
					(fill yes)
				)
			)
		)
		(pad "2" smd custom
			(at 0 0.762 90)
			(size 0.2159 0.2159)
			(layers "F.Cu" "F.Mask" "F.Paste")
			(net "FAN_2_TACH0")
			(options
				(clearance outline)
				(anchor circle)
			)
			(primitives
				(gr_poly
					(pts
						(arc
							(start -0.3302 -0.4318)
							(mid -0.402042 -0.402042)
							(end -0.4318 -0.3302)
						)
						(arc
							(start -0.4318 0.3302)
							(mid -0.402042 0.402042)
							(end -0.3302 0.4318)
						)
						(arc
							(start 0.3302 0.4318)
							(mid 0.402042 0.402042)
							(end 0.4318 0.3302)
						)
						(arc
							(start 0.4318 -0.3302)
							(mid 0.402042 -0.402042)
							(end 0.3302 -0.4318)
						)
					)
					(width 0)
					(fill yes)
				)
			)
		)
	)
	(footprint ""
		(layer "F.Cu")
		(at 176.657 -150.622 90)
		(property "Reference" "R462"
			(at 0 0 90)
			(layer "F.SilkS")
			(hide yes)
			(effects
				(font
					(size 1.27 1.27)
				)
			)
		)
		(property "Value" "2R6F-GP"
			(at -0.0508 -4.8514 90)
			(unlocked yes)
			(layer "F.Fab")
			(hide yes)
			(effects
				(font
					(size 1.016 1.016)
					(thickness 0.1524)
				)
			)
		)
		(property "Device Type" "R1206H26"
			(at 0 -6.3754 90)
			(unlocked yes)
			(layer "F.Fab")
			(hide yes)
			(effects
				(font
					(size 1.016 1.016)
					(thickness 0.1524)
				)
			)
		)
		(duplicate_pad_numbers_are_jumpers no)
		(fp_line
			(start 1.016 -2.2352)
			(end 1.016 2.2352)
			(stroke
				(width 0.1524)
				(type default)
			)
			(layer "F.SilkS")
		)
		(fp_line
			(start -1.016 -2.2352)
			(end 1.016 -2.2352)
			(stroke
				(width 0.1524)
				(type default)
			)
			(layer "F.SilkS")
		)
		(fp_line
			(start 1.016 2.2352)
			(end -1.016 2.2352)
			(stroke
				(width 0.1524)
				(type default)
			)
			(layer "F.SilkS")
		)
		(fp_line
			(start -1.016 2.2352)
			(end -1.016 -2.2352)
			(stroke
				(width 0.1524)
				(type default)
			)
			(layer "F.SilkS")
		)
		(fp_rect
			(start -1.0922 2.3114)
			(end 1.0922 -2.3114)
			(stroke
				(width 0)
				(type default)
			)
			(fill no)
			(layer "F.CrtYd")
		)
		(fp_poly
			(pts
				(xy -1.0922 -2.3114) (xy 1.0922 -2.3114) (xy 1.0922 2.3114) (xy -1.0922 2.3114)
			)
			(stroke
				(width 0)
				(type default)
			)
			(fill no)
			(layer "F.Fab")
		)
		(pad "1" smd rect
			(at 0 -1.397 90)
			(size 1.651 1.27)
			(layers "F.Cu" "F.Mask" "F.Paste")
			(net "P12V_HDD17")
		)
		(pad "2" smd rect
			(at 0 1.397 90)
			(size 1.651 1.27)
			(layers "F.Cu" "F.Mask" "F.Paste")
			(net "12V_PRE_17")
		)
	)
	(footprint ""
		(layer "F.Cu")
		(at 368.808 -133.858 90)
		(property "Reference" "D19"
			(at 0 0 90)
			(layer "F.SilkS")
			(hide yes)
			(effects
				(font
					(size 1.27 1.27)
				)
			)
		)
		(property "Value" "RB551V30-GP"
			(at 0 -6.7818 90)
			(unlocked yes)
			(layer "F.Fab")
			(hide yes)
			(effects
				(font
					(size 1.016 1.016)
					(thickness 0.1524)
				)
			)
		)
		(property "Device Type" "SOD323AKH38"
			(at 0 -8.6868 90)
			(unlocked yes)
			(layer "F.Fab")
			(hide yes)
			(effects
				(font
					(size 1.016 1.016)
					(thickness 0.1524)
				)
			)
		)
		(duplicate_pad_numbers_are_jumpers no)
		(fp_line
			(start 0.889 -1.9304)
			(end 0.889 2.159)
			(stroke
				(width 0.1524)
				(type default)
			)
			(layer "F.SilkS")
		)
		(fp_line
			(start -0.889 -1.9304)
			(end 0.889 -1.9304)
			(stroke
				(width 0.1524)
				(type default)
			)
			(layer "F.SilkS")
		)
		(fp_line
			(start 0.762 2.0574)
			(end -0.762 2.0574)
			(stroke
				(width 0.508)
				(type default)
			)
			(layer "F.SilkS")
		)
		(fp_line
			(start 0.889 2.159)
			(end -0.889 2.159)
			(stroke
				(width 0.1524)
				(type default)
			)
			(layer "F.SilkS")
		)
		(fp_line
			(start -0.889 2.159)
			(end -0.889 -1.9304)
			(stroke
				(width 0.1524)
				(type default)
			)
			(layer "F.SilkS")
		)
		(fp_rect
			(start -1.016 2.3114)
			(end 1.016 -2.0066)
			(stroke
				(width 0)
				(type default)
			)
			(fill no)
			(layer "F.CrtYd")
		)
		(fp_poly
			(pts
				(xy -1.016 -2.0066) (xy 1.016 -2.0066) (xy 1.016 2.3114) (xy -1.016 2.3114)
			)
			(stroke
				(width 0)
				(type default)
			)
			(fill no)
			(layer "F.Fab")
		)
		(pad "A" smd rect
			(at 0 -1.143 90)
			(size 0.5588 1.016)
			(layers "F.Cu" "F.Mask" "F.Paste")
			(net "SW_HDD_R19")
		)
		(pad "K" smd rect
			(at 0 1.143 90)
			(size 0.5588 1.016)
			(layers "F.Cu" "F.Mask" "F.Paste")
			(net "SW_HDD_N19")
		)
	)
	(footprint ""
		(layer "F.Cu")
		(at 220.963998 -352.711766)
		(property "Reference" "R1021"
			(at 0 0 0)
			(layer "F.SilkS")
			(hide yes)
			(effects
				(font
					(size 1.27 1.27)
				)
			)
		)
		(property "Value" "1KR2J-1-GP"
			(at 0.064008 -3.993896 0)
			(unlocked yes)
			(layer "F.Fab")
			(hide yes)
			(effects
				(font
					(size 1.016 1.016)
					(thickness 0.1524)
				)
			)
		)
		(property "Device Type" "R402H16"
			(at 0.064008 -5.517896 0)
			(unlocked yes)
			(layer "F.Fab")
			(hide yes)
			(effects
				(font
					(size 1.016 1.016)
					(thickness 0.1524)
				)
			)
		)
		(duplicate_pad_numbers_are_jumpers no)
		(fp_line
			(start -0.508 -0.9398)
			(end -0.508 0.9398)
			(stroke
				(width 0.1524)
				(type default)
			)
			(layer "F.SilkS")
		)
		(fp_line
			(start 0.508 -0.9398)
			(end -0.508 -0.9398)
			(stroke
				(width 0.1524)
				(type default)
			)
			(layer "F.SilkS")
		)
		(fp_rect
			(start -0.508 0.9398)
			(end 0.508 -0.9398)
			(stroke
				(width 0)
				(type default)
			)
			(fill no)
			(layer "F.CrtYd")
		)
		(fp_rect
			(start -0.508 0.9398)
			(end 0.508 -0.9398)
			(stroke
				(width 0)
				(type default)
			)
			(fill no)
			(layer "F.Fab")
		)
		(pad "1" smd custom
			(at 0 -0.4445)
			(size 0.1397 0.1397)
			(layers "F.Cu" "F.Mask" "F.Paste")
			(net "MB0_CM_VOUT_R")
			(options
				(clearance outline)
				(anchor circle)
			)
			(primitives
				(gr_poly
					(pts
						(arc
							(start -0.1778 -0.2794)
							(mid -0.249642 -0.249642)
							(end -0.2794 -0.1778)
						)
						(arc
							(start -0.2794 0.1778)
							(mid -0.249642 0.249642)
							(end -0.1778 0.2794)
						)
						(arc
							(start 0.1778 0.2794)
							(mid 0.249642 0.249642)
							(end 0.2794 0.1778)
						)
						(arc
							(start 0.2794 -0.1778)
							(mid 0.249642 -0.249642)
							(end 0.1778 -0.2794)
						)
					)
					(width 0)
					(fill yes)
				)
			)
		)
		(pad "2" smd custom
			(at 0 0.4445)
			(size 0.1397 0.1397)
			(layers "F.Cu" "F.Mask" "F.Paste")
			(net "P12V_IN")
			(options
				(clearance outline)
				(anchor circle)
			)
			(primitives
				(gr_poly
					(pts
						(arc
							(start -0.1778 -0.2794)
							(mid -0.249642 -0.249642)
							(end -0.2794 -0.1778)
						)
						(arc
							(start -0.2794 0.1778)
							(mid -0.249642 0.249642)
							(end -0.1778 0.2794)
						)
						(arc
							(start 0.1778 0.2794)
							(mid 0.249642 0.249642)
							(end 0.2794 0.1778)
						)
						(arc
							(start 0.2794 -0.1778)
							(mid 0.249642 -0.249642)
							(end 0.1778 -0.2794)
						)
					)
					(width 0)
					(fill yes)
				)
			)
		)
	)
	(footprint ""
		(layer "F.Cu")
		(at 478.79 -148.209)
		(property "Reference" "R598"
			(at 0 0 0)
			(layer "F.SilkS")
			(hide yes)
			(effects
				(font
					(size 1.27 1.27)
				)
			)
		)
		(property "Value" "2R6F-GP"
			(at -0.0508 -4.8514 0)
			(unlocked yes)
			(layer "F.Fab")
			(hide yes)
			(effects
				(font
					(size 1.016 1.016)
					(thickness 0.1524)
				)
			)
		)
		(property "Device Type" "R1206H26"
			(at 0 -6.3754 0)
			(unlocked yes)
			(layer "F.Fab")
			(hide yes)
			(effects
				(font
					(size 1.016 1.016)
					(thickness 0.1524)
				)
			)
		)
		(duplicate_pad_numbers_are_jumpers no)
		(fp_line
			(start -1.016 -2.2352)
			(end 1.016 -2.2352)
			(stroke
				(width 0.1524)
				(type default)
			)
			(layer "F.SilkS")
		)
		(fp_line
			(start -1.016 2.2352)
			(end -1.016 -2.2352)
			(stroke
				(width 0.1524)
				(type default)
			)
			(layer "F.SilkS")
		)
		(fp_line
			(start 1.016 -2.2352)
			(end 1.016 2.2352)
			(stroke
				(width 0.1524)
				(type default)
			)
			(layer "F.SilkS")
		)
		(fp_line
			(start 1.016 2.2352)
			(end -1.016 2.2352)
			(stroke
				(width 0.1524)
				(type default)
			)
			(layer "F.SilkS")
		)
		(fp_rect
			(start -1.0922 2.3114)
			(end 1.0922 -2.3114)
			(stroke
				(width 0)
				(type default)
			)
			(fill no)
			(layer "F.CrtYd")
		)
		(fp_poly
			(pts
				(xy -1.0922 -2.3114) (xy 1.0922 -2.3114) (xy 1.0922 2.3114) (xy -1.0922 2.3114)
			)
			(stroke
				(width 0)
				(type default)
			)
			(fill no)
			(layer "F.Fab")
		)
		(pad "1" smd rect
			(at 0 -1.397)
			(size 1.651 1.27)
			(layers "F.Cu" "F.Mask" "F.Paste")
			(net "P5V_HDD23")
		)
		(pad "2" smd rect
			(at 0 1.397)
			(size 1.651 1.27)
			(layers "F.Cu" "F.Mask" "F.Paste")
			(net "5V_PRE_23")
		)
	)
	(footprint ""
		(layer "F.Cu")
		(at 146.939 -26.289 180)
		(property "Reference" "Q142"
			(at 0 0 180)
			(layer "F.SilkS")
			(hide yes)
			(effects
				(font
					(size 1.27 1.27)
				)
			)
		)
		(property "Value" "AO4406AL-GP"
			(at -3.707384 -1.5367 180)
			(unlocked yes)
			(layer "F.Fab")
			(hide yes)
			(effects
				(font
					(size 1.016 1.016)
					(thickness 0.1524)
				)
			)
		)
		(property "Device Type" "SOIC8H69"
			(at -3.707384 -3.0607 180)
			(unlocked yes)
			(layer "F.Fab")
			(hide yes)
			(effects
				(font
					(size 1.016 1.016)
					(thickness 0.1524)
				)
			)
		)
		(duplicate_pad_numbers_are_jumpers no)
		(fp_line
			(start 2.1336 1.4224)
			(end 2.1336 -1.4224)
			(stroke
				(width 0.1524)
				(type default)
			)
			(layer "F.SilkS")
		)
		(fp_line
			(start 2.1336 -1.4224)
			(end -2.7432 -1.4224)
			(stroke
				(width 0.1524)
				(type default)
			)
			(layer "F.SilkS")
		)
		(fp_line
			(start -2.1844 -0.0508)
			(end -2.7178 0.508)
			(stroke
				(width 0.1524)
				(type default)
			)
			(layer "F.SilkS")
		)
		(fp_line
			(start -2.6289 3.4417)
			(end -2.6289 1.4732)
			(stroke
				(width 0.381)
				(type default)
			)
			(layer "F.SilkS")
		)
		(fp_line
			(start -2.7178 -0.508)
			(end -2.1844 -0.0508)
			(stroke
				(width 0.1524)
				(type default)
			)
			(layer "F.SilkS")
		)
		(fp_line
			(start -2.7432 1.4224)
			(end 2.1336 1.4224)
			(stroke
				(width 0.1524)
				(type default)
			)
			(layer "F.SilkS")
		)
		(fp_line
			(start -2.7432 1.4224)
			(end -2.6416 1.4224)
			(stroke
				(width 0.1524)
				(type default)
			)
			(layer "F.SilkS")
		)
		(fp_line
			(start -2.7432 -1.4224)
			(end -2.7432 1.4224)
			(stroke
				(width 0.1524)
				(type default)
			)
			(layer "F.SilkS")
		)
		(fp_poly
			(pts
				(xy -2.2098 -1.4224) (xy -2.2098 1.4224) (xy 2.2098 1.4224) (xy 2.2098 -1.4224)
			)
			(stroke
				(width 0)
				(type default)
			)
			(fill yes)
			(layer "F.SilkS")
		)
		(fp_rect
			(start -2.450084 2.999994)
			(end 2.450084 -2.999994)
			(stroke
				(width 0)
				(type default)
			)
			(fill no)
			(layer "F.CrtYd")
		)
		(fp_poly
			(pts
				(xy -2.8194 3.6322) (xy -2.8194 -3.6322) (xy 2.8194 -3.6322) (xy 2.8194 1.18364) (xy 2.450084 1.18364)
				(xy 2.450084 -2.999994) (xy -2.450084 -2.999994) (xy -2.450084 2.999994) (xy 2.450084 2.999994)
				(xy 2.450084 1.18618) (xy 2.8194 1.18618) (xy 2.8194 3.6322)
			)
			(stroke
				(width 0)
				(type default)
			)
			(fill no)
			(layer "F.CrtYd")
		)
		(fp_rect
			(start -2.8194 3.6322)
			(end 2.8194 -3.6322)
			(stroke
				(width 0)
				(type default)
			)
			(fill no)
			(layer "F.Fab")
		)
		(pad "1" smd rect
			(at -1.905 2.54 180)
			(size 0.635 1.651)
			(layers "F.Cu" "F.Mask" "F.Paste")
			(net "P5V_HDD28")
		)
		(pad "2" smd rect
			(at -0.635 2.54 180)
			(size 0.635 1.651)
			(layers "F.Cu" "F.Mask" "F.Paste")
			(net "P5V_HDD28")
		)
		(pad "3" smd rect
			(at 0.635 2.54 180)
			(size 0.635 1.651)
			(layers "F.Cu" "F.Mask" "F.Paste")
			(net "P5V_HDD28")
		)
		(pad "4" smd rect
			(at 1.905 2.54 180)
			(size 0.635 1.651)
			(layers "F.Cu" "F.Mask" "F.Paste")
			(net "SW_HDD_P28")
		)
		(pad "5" smd rect
			(at 1.905 -2.54 180)
			(size 0.635 1.651)
			(layers "F.Cu" "F.Mask" "F.Paste")
			(net "P5V_B_2")
		)
		(pad "6" smd rect
			(at 0.635 -2.54 180)
			(size 0.635 1.651)
			(layers "F.Cu" "F.Mask" "F.Paste")
			(net "P5V_B_2")
		)
		(pad "7" smd rect
			(at -0.635 -2.54 180)
			(size 0.635 1.651)
			(layers "F.Cu" "F.Mask" "F.Paste")
			(net "P5V_B_2")
		)
		(pad "8" smd rect
			(at -1.905 -2.54 180)
			(size 0.635 1.651)
			(layers "F.Cu" "F.Mask" "F.Paste")
			(net "P5V_B_2")
		)
	)
)
